(kicad_pcb
	(version 20241229)
	(generator "pcbnew")
	(generator_version "9.0")
	(general
		(thickness 1.6)
		(legacy_teardrops no)
	)
	(paper "A4")
	(title_block
		(title "environment-sensor")
		(comment 1 "footprints 42-46 of 109")
	)
	(layers
		(0 "F.Cu" signal)
		(4 "In1.Cu" signal)
		(6 "In2.Cu" signal)
		(2 "B.Cu" signal)
		(9 "F.Adhes" user "F.Adhesive")
		(11 "B.Adhes" user "B.Adhesive")
		(13 "F.Paste" user)
		(15 "B.Paste" user)
		(5 "F.SilkS" user "F.Silkscreen")
		(7 "B.SilkS" user "B.Silkscreen")
		(1 "F.Mask" user)
		(3 "B.Mask" user)
		(17 "Dwgs.User" user "User.Drawings")
		(19 "Cmts.User" user "User.Comments")
		(21 "Eco1.User" user "User.Eco1")
		(23 "Eco2.User" user "User.Eco2")
		(25 "Edge.Cuts" user)
		(27 "Margin" user)
		(31 "F.CrtYd" user "F.Courtyard")
		(29 "B.CrtYd" user "B.Courtyard")
		(35 "F.Fab" user)
		(33 "B.Fab" user)
	)
	(footprint "antmicro-footprints:R_0402_1005Metric"
		(layer "F.Cu")
		(at 182.736 121.6625 180)
		(descr "Resistor SMD 0402")
		(tags "resistor SMD 0402")
		(property "Reference" "R33"
			(at 3.136 -0.3595 0)
			(layer "F.SilkS")
			(effects
				(font
					(size 0.7 0.7)
					(thickness 0.15)
				)
				(justify left bottom)
			)
		)
		(property "Value" "R_100k_0402"
			(at 0 1.4 180)
			(layer "F.Fab")
			(effects
				(font
					(size 0.7 0.7)
					(thickness 0.15)
				)
				(justify left bottom)
			)
		)
		(property "Description" "SMD Chip Resistor, 100 kohm, ± 1%, 62.5 mW, 0402 [1005 Metric], Thick Film, General Purpose"
			(at 0 0 180)
			(layer "F.Fab")
			(hide yes)
			(effects
				(font
					(size 1.27 1.27)
					(thickness 0.15)
				)
			)
		)
		(property "Author" "Antmicro"
			(at 365.472 243.325 0)
			(layer "F.Fab")
			(hide yes)
			(effects
				(font
					(size 1 1)
					(thickness 0.15)
				)
			)
		)
		(property "License" "Apache-2.0"
			(at 365.472 243.325 0)
			(layer "F.Fab")
			(hide yes)
			(effects
				(font
					(size 1 1)
					(thickness 0.15)
				)
			)
		)
		(property "MPN" "CR0402-FX-1003GLF"
			(at 365.472 243.325 0)
			(layer "F.Fab")
			(hide yes)
			(effects
				(font
					(size 1 1)
					(thickness 0.15)
				)
			)
		)
		(property "Manufacturer" "Bourns"
			(at 365.472 243.325 0)
			(layer "F.Fab")
			(hide yes)
			(effects
				(font
					(size 1 1)
					(thickness 0.15)
				)
			)
		)
		(property "Public" "False"
			(at 365.472 243.325 0)
			(layer "F.Fab")
			(hide yes)
			(effects
				(font
					(size 1 1)
					(thickness 0.15)
				)
			)
		)
		(property "Tolerance" "1%"
			(at 365.472 243.325 0)
			(layer "F.Fab")
			(hide yes)
			(effects
				(font
					(size 1 1)
					(thickness 0.15)
				)
			)
		)
		(property "Val" "100k"
			(at 365.472 243.325 0)
			(layer "F.Fab")
			(hide yes)
			(effects
				(font
					(size 1 1)
					(thickness 0.15)
				)
			)
		)
		(sheetfile "environment-sensor.kicad_sch")
		(attr smd exclude_from_pos_files exclude_from_bom dnp)
		(fp_rect
			(start -0.925 -0.47)
			(end 0.925 0.47)
			(stroke
				(width 0.05)
				(type default)
			)
			(fill no)
			(layer "F.CrtYd")
		)
		(fp_rect
			(start -0.5 -0.25)
			(end 0.5 0.25)
			(stroke
				(width 0.15)
				(type solid)
			)
			(fill no)
			(layer "F.Fab")
		)
		(pad "1" smd roundrect
			(at -0.48 0 180)
			(size 0.59 0.64)
			(layers "F.Cu" "F.Mask" "F.Paste")
			(roundrect_rratio 0.25)
			(net 52 "Net-(U4-A2)")
			(pintype "passive")
		)
		(pad "2" smd roundrect
			(at 0.48 0 180)
			(size 0.59 0.64)
			(layers "F.Cu" "F.Mask" "F.Paste")
			(roundrect_rratio 0.25)
			(net 2 "+3V3")
			(pintype "passive")
		)
	)
	(footprint "antmicro-footprints:C_0402_1005Metric"
		(layer "F.Cu")
		(at 201.25 115.85 90)
		(descr "Capacitor SMD 0402")
		(tags "capacitor SMD 0402")
		(property "Reference" "C25"
			(at 1.06 -1.3 180)
			(layer "F.SilkS")
			(effects
				(font
					(size 0.7 0.7)
					(thickness 0.15)
				)
				(justify left bottom)
			)
		)
		(property "Value" "C_100n_0402"
			(at 0 1.4 90)
			(layer "F.Fab")
			(effects
				(font
					(size 0.7 0.7)
					(thickness 0.15)
				)
				(justify left bottom)
			)
		)
		(property "Description" "SMD Multilayer Ceramic Capacitor, 0.1 µF, 50 V, 0402 [1005 Metric], ± 10%, X5R, GRM Series"
			(at 0 0 90)
			(layer "F.Fab")
			(hide yes)
			(effects
				(font
					(size 1.27 1.27)
					(thickness 0.15)
				)
			)
		)
		(property "Author" "Antmicro"
			(at 317.1 -85.4 0)
			(layer "F.Fab")
			(hide yes)
			(effects
				(font
					(size 1 1)
					(thickness 0.15)
				)
			)
		)
		(property "Dielectric" "X5R"
			(at 317.1 -85.4 0)
			(layer "F.Fab")
			(hide yes)
			(effects
				(font
					(size 1 1)
					(thickness 0.15)
				)
			)
		)
		(property "License" "Apache-2.0"
			(at 317.1 -85.4 0)
			(layer "F.Fab")
			(hide yes)
			(effects
				(font
					(size 1 1)
					(thickness 0.15)
				)
			)
		)
		(property "MPN" "GRM155R61H104KE14D"
			(at 317.1 -85.4 0)
			(layer "F.Fab")
			(hide yes)
			(effects
				(font
					(size 1 1)
					(thickness 0.15)
				)
			)
		)
		(property "Manufacturer" "Murata"
			(at 317.1 -85.4 0)
			(layer "F.Fab")
			(hide yes)
			(effects
				(font
					(size 1 1)
					(thickness 0.15)
				)
			)
		)
		(property "Public" "False"
			(at 317.1 -85.4 0)
			(layer "F.Fab")
			(hide yes)
			(effects
				(font
					(size 1 1)
					(thickness 0.15)
				)
			)
		)
		(property "Val" "100n"
			(at 317.1 -85.4 0)
			(layer "F.Fab")
			(hide yes)
			(effects
				(font
					(size 1 1)
					(thickness 0.15)
				)
			)
		)
		(property "Voltage" "50V"
			(at 317.1 -85.4 0)
			(layer "F.Fab")
			(hide yes)
			(effects
				(font
					(size 1 1)
					(thickness 0.15)
				)
			)
		)
		(sheetfile "environment-sensor.kicad_sch")
		(attr smd)
		(fp_rect
			(start -0.925 -0.47)
			(end 0.925 0.47)
			(stroke
				(width 0.05)
				(type default)
			)
			(fill no)
			(layer "F.CrtYd")
		)
		(fp_line
			(start 0.504 -0.25)
			(end 0.504 0.248)
			(stroke
				(width 0.15)
				(type solid)
			)
			(layer "F.Fab")
		)
		(fp_line
			(start -0.494 -0.25)
			(end 0.504 -0.25)
			(stroke
				(width 0.15)
				(type solid)
			)
			(layer "F.Fab")
		)
		(fp_line
			(start 0.504 0.248)
			(end -0.494 0.248)
			(stroke
				(width 0.15)
				(type solid)
			)
			(layer "F.Fab")
		)
		(fp_line
			(start -0.494 0.248)
			(end -0.494 -0.25)
			(stroke
				(width 0.15)
				(type solid)
			)
			(layer "F.Fab")
		)
		(pad "1" smd roundrect
			(at -0.48 0 90)
			(size 0.59 0.64)
			(layers "F.Cu" "F.Mask" "F.Paste")
			(roundrect_rratio 0.25)
			(net 2 "+3V3")
			(pintype "passive")
		)
		(pad "2" smd roundrect
			(at 0.48 0 90)
			(size 0.59 0.64)
			(layers "F.Cu" "F.Mask" "F.Paste")
			(roundrect_rratio 0.25)
			(net 1 "GND")
			(pintype "passive")
		)
	)
	(footprint "antmicro-footprints:R_0402_1005Metric"
		(layer "F.Cu")
		(at 182.729 118.5625 180)
		(descr "Resistor SMD 0402")
		(tags "resistor SMD 0402")
		(property "Reference" "R31"
			(at 3.129 -0.3635 0)
			(layer "F.SilkS")
			(effects
				(font
					(size 0.7 0.7)
					(thickness 0.15)
				)
				(justify left bottom)
			)
		)
		(property "Value" "R_100k_0402"
			(at 0 1.4 180)
			(layer "F.Fab")
			(effects
				(font
					(size 0.7 0.7)
					(thickness 0.15)
				)
				(justify left bottom)
			)
		)
		(property "Description" "SMD Chip Resistor, 100 kohm, ± 1%, 62.5 mW, 0402 [1005 Metric], Thick Film, General Purpose"
			(at 0 0 180)
			(layer "F.Fab")
			(hide yes)
			(effects
				(font
					(size 1.27 1.27)
					(thickness 0.15)
				)
			)
		)
		(property "Author" "Antmicro"
			(at 365.458 237.125 0)
			(layer "F.Fab")
			(hide yes)
			(effects
				(font
					(size 1 1)
					(thickness 0.15)
				)
			)
		)
		(property "License" "Apache-2.0"
			(at 365.458 237.125 0)
			(layer "F.Fab")
			(hide yes)
			(effects
				(font
					(size 1 1)
					(thickness 0.15)
				)
			)
		)
		(property "MPN" "CR0402-FX-1003GLF"
			(at 365.458 237.125 0)
			(layer "F.Fab")
			(hide yes)
			(effects
				(font
					(size 1 1)
					(thickness 0.15)
				)
			)
		)
		(property "Manufacturer" "Bourns"
			(at 365.458 237.125 0)
			(layer "F.Fab")
			(hide yes)
			(effects
				(font
					(size 1 1)
					(thickness 0.15)
				)
			)
		)
		(property "Public" "False"
			(at 365.458 237.125 0)
			(layer "F.Fab")
			(hide yes)
			(effects
				(font
					(size 1 1)
					(thickness 0.15)
				)
			)
		)
		(property "Tolerance" "1%"
			(at 365.458 237.125 0)
			(layer "F.Fab")
			(hide yes)
			(effects
				(font
					(size 1 1)
					(thickness 0.15)
				)
			)
		)
		(property "Val" "100k"
			(at 365.458 237.125 0)
			(layer "F.Fab")
			(hide yes)
			(effects
				(font
					(size 1 1)
					(thickness 0.15)
				)
			)
		)
		(sheetfile "environment-sensor.kicad_sch")
		(attr smd exclude_from_pos_files exclude_from_bom dnp)
		(fp_rect
			(start -0.925 -0.47)
			(end 0.925 0.47)
			(stroke
				(width 0.05)
				(type default)
			)
			(fill no)
			(layer "F.CrtYd")
		)
		(fp_rect
			(start -0.5 -0.25)
			(end 0.5 0.25)
			(stroke
				(width 0.15)
				(type solid)
			)
			(fill no)
			(layer "F.Fab")
		)
		(pad "1" smd roundrect
			(at -0.48 0 180)
			(size 0.59 0.64)
			(layers "F.Cu" "F.Mask" "F.Paste")
			(roundrect_rratio 0.25)
			(net 51 "Net-(U4-A1)")
			(pintype "passive")
		)
		(pad "2" smd roundrect
			(at 0.48 0 180)
			(size 0.59 0.64)
			(layers "F.Cu" "F.Mask" "F.Paste")
			(roundrect_rratio 0.25)
			(net 2 "+3V3")
			(pintype "passive")
		)
	)
	(footprint "antmicro-footprints:LED_0603_1608Metric_G"
		(layer "F.Cu")
		(at 172.15 138.7)
		(descr "LED SMD 0603 Green")
		(tags "LED SMD 0603 Green")
		(property "Reference" "LD1"
			(at 26.6 0.9 0)
			(layer "F.SilkS")
			(effects
				(font
					(size 0.7 0.7)
					(thickness 0.15)
				)
				(justify left bottom)
			)
		)
		(property "Value" "LED_G_0603_KP-1608ZGC"
			(at 0 1.6 0)
			(layer "F.Fab")
			(effects
				(font
					(size 0.7 0.7)
					(thickness 0.15)
				)
				(justify left bottom)
			)
		)
		(property "Description" "LED, Green, SMD, 0603, 20 mA, 3.3 V, 525 nm"
			(at 0 0 0)
			(layer "F.Fab")
			(hide yes)
			(effects
				(font
					(size 1.27 1.27)
					(thickness 0.15)
				)
			)
		)
		(property "Author" "Antmicro"
			(at 0 0 0)
			(layer "F.Fab")
			(hide yes)
			(effects
				(font
					(size 1 1)
					(thickness 0.15)
				)
			)
		)
		(property "Color" "Green"
			(at 0 0 0)
			(layer "F.Fab")
			(hide yes)
			(effects
				(font
					(size 1 1)
					(thickness 0.15)
				)
			)
		)
		(property "License" "Apache-2.0"
			(at 0 0 0)
			(layer "F.Fab")
			(hide yes)
			(effects
				(font
					(size 1 1)
					(thickness 0.15)
				)
			)
		)
		(property "MPN" "KP-1608ZGC"
			(at 0 0 0)
			(layer "F.Fab")
			(hide yes)
			(effects
				(font
					(size 1 1)
					(thickness 0.15)
				)
			)
		)
		(property "Manufacturer" "Kingbright"
			(at 0 0 0)
			(layer "F.Fab")
			(hide yes)
			(effects
				(font
					(size 1 1)
					(thickness 0.15)
				)
			)
		)
		(property "Public" "False"
			(at 0 0 0)
			(layer "F.Fab")
			(hide yes)
			(effects
				(font
					(size 1 1)
					(thickness 0.15)
				)
			)
		)
		(sheetfile "environment-sensor.kicad_sch")
		(attr smd)
		(fp_line
			(start -1.18 -0.319)
			(end -1.18 0.321)
			(stroke
				(width 0.15)
				(type solid)
			)
			(layer "F.SilkS")
		)
		(fp_line
			(start -0.094672 0.001008)
			(end -0.24 0.001008)
			(stroke
				(width 0.1)
				(type solid)
			)
			(layer "F.SilkS")
		)
		(fp_line
			(start -0.094672 0.001008)
			(end 0.105328 -0.198992)
			(stroke
				(width 0.1)
				(type solid)
			)
			(layer "F.SilkS")
		)
		(fp_line
			(start -0.094672 0.201008)
			(end -0.094672 -0.198992)
			(stroke
				(width 0.1)
				(type solid)
			)
			(layer "F.SilkS")
		)
		(fp_line
			(start 0.105328 0.001008)
			(end 0.24 0.001)
			(stroke
				(width 0.1)
				(type solid)
			)
			(layer "F.SilkS")
		)
		(fp_line
			(start 0.105328 0.201008)
			(end -0.094672 0.001008)
			(stroke
				(width 0.1)
				(type solid)
			)
			(layer "F.SilkS")
		)
		(fp_line
			(start 0.105328 0.201008)
			(end 0.105328 -0.198992)
			(stroke
				(width 0.1)
				(type solid)
			)
			(layer "F.SilkS")
		)
		(fp_line
			(start 0.22 -0.35)
			(end -0.22 -0.35)
			(stroke
				(width 0.15)
				(type solid)
			)
			(layer "F.SilkS")
		)
		(fp_line
			(start 0.22 0.35)
			(end -0.22 0.35)
			(stroke
				(width 0.15)
				(type solid)
			)
			(layer "F.SilkS")
		)
		(fp_rect
			(start 1.25 0.65)
			(end -1.25 -0.65)
			(stroke
				(width 0.05)
				(type solid)
			)
			(fill no)
			(layer "F.CrtYd")
		)
		(fp_line
			(start -0.199 -0.202)
			(end -0.199 0.1)
			(stroke
				(width 0.15)
				(type solid)
			)
			(layer "F.Fab")
		)
		(fp_line
			(start -0.199 0)
			(end -0.597 0)
			(stroke
				(width 0.15)
				(type solid)
			)
			(layer "F.Fab")
		)
		(fp_line
			(start -0.199 0.2)
			(end -0.199 0.1)
			(stroke
				(width 0.15)
				(type solid)
			)
			(layer "F.Fab")
		)
		(fp_line
			(start -0.101 0)
			(end 0.201 0.2)
			(stroke
				(width 0.15)
				(type solid)
			)
			(layer "F.Fab")
		)
		(fp_line
			(start 0.201 -0.202)
			(end -0.101 0)
			(stroke
				(width 0.15)
				(type solid)
			)
			(layer "F.Fab")
		)
		(fp_line
			(start 0.201 0)
			(end 0.201 -0.202)
			(stroke
				(width 0.15)
				(type solid)
			)
			(layer "F.Fab")
		)
		(fp_line
			(start 0.201 0.2)
			(end 0.201 0)
			(stroke
				(width 0.15)
				(type solid)
			)
			(layer "F.Fab")
		)
		(fp_line
			(start 0.599 0)
			(end 0.201 0)
			(stroke
				(width 0.15)
				(type solid)
			)
			(layer "F.Fab")
		)
		(fp_rect
			(start 0.848 0.4)
			(end -0.85 -0.402)
			(stroke
				(width 0.15)
				(type solid)
			)
			(fill no)
			(layer "F.Fab")
		)
		(pad "1" smd roundrect
			(at -0.7 0 180)
			(size 0.8 1)
			(layers "F.Cu" "F.Mask" "F.Paste")
			(roundrect_rratio 0.2)
			(net 26 "+5V")
			(pinfunction "C")
			(pintype "passive")
		)
		(pad "2" smd roundrect
			(at 0.7 0 180)
			(size 0.8 1)
			(layers "F.Cu" "F.Mask" "F.Paste")
			(roundrect_rratio 0.2)
			(net 10 "Net-(LD1-A)")
			(pinfunction "A")
			(pintype "passive")
		)
	)
	(footprint "antmicro-footprints:C_0402_1005Metric"
		(layer "F.Cu")
		(at 194.05 138.4 -90)
		(descr "Capacitor SMD 0402")
		(tags "capacitor SMD 0402")
		(property "Reference" "C20"
			(at -15.757 9.2655 90)
			(layer "B.SilkS")
			(effects
				(font
					(size 0.7 0.7)
					(thickness 0.15)
				)
				(justify right bottom mirror)
			)
		)
		(property "Value" "C_2u2_0402"
			(at 0 1.4 90)
			(layer "F.Fab")
			(effects
				(font
					(size 0.7 0.7)
					(thickness 0.15)
				)
				(justify right bottom)
			)
		)
		(property "Description" "SMD Multilayer Ceramic Capacitor, 2.2 µF, 10 V, 0402 [1005 Metric], ± 10%, X5R, C"
			(at 0 0 270)
			(layer "F.Fab")
			(hide yes)
			(effects
				(font
					(size 1.27 1.27)
					(thickness 0.15)
				)
			)
		)
		(property "Author" "Antmicro"
			(at 55.65 332.45 0)
			(layer "F.Fab")
			(hide yes)
			(effects
				(font
					(size 1 1)
					(thickness 0.15)
				)
			)
		)
		(property "Dielectric" ""
			(at 55.65 332.45 0)
			(layer "F.Fab")
			(hide yes)
			(effects
				(font
					(size 1 1)
					(thickness 0.15)
				)
			)
		)
		(property "License" "Apache-2.0"
			(at 55.65 332.45 0)
			(layer "F.Fab")
			(hide yes)
			(effects
				(font
					(size 1 1)
					(thickness 0.15)
				)
			)
		)
		(property "MPN" "C1005X5R1A225K050BC"
			(at 55.65 332.45 0)
			(layer "F.Fab")
			(hide yes)
			(effects
				(font
					(size 1 1)
					(thickness 0.15)
				)
			)
		)
		(property "Manufacturer" "TDK"
			(at 55.65 332.45 0)
			(layer "F.Fab")
			(hide yes)
			(effects
				(font
					(size 1 1)
					(thickness 0.15)
				)
			)
		)
		(property "Public" "False"
			(at 55.65 332.45 0)
			(layer "F.Fab")
			(hide yes)
			(effects
				(font
					(size 1 1)
					(thickness 0.15)
				)
			)
		)
		(property "Val" "2u2"
			(at 55.65 332.45 0)
			(layer "F.Fab")
			(hide yes)
			(effects
				(font
					(size 1 1)
					(thickness 0.15)
				)
			)
		)
		(property "Voltage" ""
			(at 55.65 332.45 0)
			(layer "F.Fab")
			(hide yes)
			(effects
				(font
					(size 1 1)
					(thickness 0.15)
				)
			)
		)
		(sheetfile "environment-sensor.kicad_sch")
		(attr smd)
		(fp_rect
			(start -0.925 -0.47)
			(end 0.925 0.47)
			(stroke
				(width 0.05)
				(type default)
			)
			(fill no)
			(layer "F.CrtYd")
		)
		(fp_line
			(start -0.494 0.248)
			(end -0.494 -0.25)
			(stroke
				(width 0.15)
				(type solid)
			)
			(layer "F.Fab")
		)
		(fp_line
			(start 0.504 0.248)
			(end -0.494 0.248)
			(stroke
				(width 0.15)
				(type solid)
			)
			(layer "F.Fab")
		)
		(fp_line
			(start -0.494 -0.25)
			(end 0.504 -0.25)
			(stroke
				(width 0.15)
				(type solid)
			)
			(layer "F.Fab")
		)
		(fp_line
			(start 0.504 -0.25)
			(end 0.504 0.248)
			(stroke
				(width 0.15)
				(type solid)
			)
			(layer "F.Fab")
		)
		(pad "1" smd roundrect
			(at -0.48 0 270)
			(size 0.59 0.64)
			(layers "F.Cu" "F.Mask" "F.Paste")
			(roundrect_rratio 0.25)
			(net 1 "GND")
			(pintype "passive")
		)
		(pad "2" smd roundrect
			(at 0.48 0 270)
			(size 0.59 0.64)
			(layers "F.Cu" "F.Mask" "F.Paste")
			(roundrect_rratio 0.25)
			(net 30 "Net-(U3-VDDA)")
			(pintype "passive")
		)
	)
)
